#ISCELL
  pure_quanta quanta_title_block_c *
  *
#ISCELL
  standard tap *
  page383_i10
#ISCELL
  standard tap *
  page383_i11
#ISCELL
  standard tap *
  page383_i12
#ISCELL
  standard tap *
  page383_i13
#ISCELL
  standard tap *
  page383_i14
#ISCELL
  standard tap *
  page383_i15
#ISCELL
  standard tap *
  page383_i16
#ISCELL
  standard tap *
  page383_i17
#ISCELL
  standard tap *
  page383_i18
#ISCELL
  standard tap *
  page383_i19
#ISCELL
  standard tap *
  page383_i20
#ISCELL
  standard offpage *
  page383_i21
#ISCELL
  standard offpage *
  page383_i22
#ISCELL
  standard tap *
  page383_i23
#ISCELL
  standard tap *
  page383_i24
#ISCELL
  standard tap *
  page383_i25
#ISCELL
  standard offpage *
  page383_i26
#ISCELL
  standard offpage *
  page383_i27
#ISCELL
  standard tap *
  page383_i28
#ISCELL
  standard tap *
  page383_i29
#CELL
  pure_quanta pt5161lrs *
  page383_i3
#ISCELL
  standard tap *
  page383_i30
#ISCELL
  standard tap *
  page383_i31
#ISCELL
  standard tap *
  page383_i32
#ISCELL
  standard tap *
  page383_i33
#ISCELL
  standard tap *
  page383_i34
#ISCELL
  standard tap *
  page383_i35
#ISCELL
  standard tap *
  page383_i36
#ISCELL
  standard tap *
  page383_i37
#ISCELL
  standard tap *
  page383_i38
#ISCELL
  standard tap *
  page383_i39
#CELL
  pure_quanta pt5161lrs *
  page383_i4
#ISCELL
  standard tap *
  page383_i40
#ISCELL
  standard tap *
  page383_i5
#ISCELL
  standard tap *
  page383_i6
#ISCELL
  standard tap *
  page383_i7
#ISCELL
  standard tap *
  page383_i8
#ISCELL
  standard tap *
  page383_i9
